FILE_TYPE = CONNECTIVITY;
{Allegro Design Entry HDL 17.4-2019 S026 (4007227) 1/17/2022}
"PAGE_NUMBER" = 384;
0"NC";
1"P5E_CPU0_P0_TX_BUF_DN<7:0>";
2"P5E_CPU0_P0_TX_BUF_DP<7:0>";
3"P5E_CPU0_P0_TX_BUF_C_DP<7:0>";
4"P5E_CPU0_P0_TX_BUF_C_DN<7:0>";
5"P5E_CPU0_P0_TX_BUF_C_DN<15:8>";
6"P5E_CPU0_P0_TX_BUF_DN<7:0>";
7"P5E_CPU0_P0_TX_BUF_DP<7:0>";
8"P5E_CPU0_P0_TX_BUF_DN<15:8>";
9"P5E_CPU0_P0_TX_BUF_DN<15:8>";
10"P5E_CPU0_P0_TX_BUF_DP<15:8>";
11"P5E_CPU0_P0_TX_BUF_DP<15:8>";
12"P5E_CPU0_P0_TX_BUF_C_DP<15:8>";
13"P5E_CPU0_P0_TX_BUF_DN<13>";
14"P5E_CPU0_P0_TX_BUF_DN<11>";
15"P5E_CPU0_P0_TX_BUF_DN<10>";
16"P5E_CPU0_P0_TX_BUF_DN<9>";
17"P5E_CPU0_P0_TX_BUF_DN<8>";
18"P5E_CPU0_P0_TX_BUF_DP<8>";
19"P5E_CPU0_P0_TX_BUF_DN<8>";
20"P5E_CPU0_P0_TX_BUF_C_DN<9>";
21"P5E_CPU0_P0_TX_BUF_DN<10>";
22"P5E_CPU0_P0_TX_BUF_C_DP<10>";
23"P5E_CPU0_P0_TX_BUF_C_DP<8>";
24"P5E_CPU0_P0_TX_BUF_C_DP<11>";
25"P5E_CPU0_P0_TX_BUF_C_DP<12>";
26"P5E_CPU0_P0_TX_BUF_C_DP<13>";
27"P5E_CPU0_P0_TX_BUF_C_DP<14>";
28"P5E_CPU0_P0_TX_BUF_C_DP<15>";
29"P5E_CPU0_P0_TX_BUF_C_DP<9>";
30"P5E_CPU0_P0_TX_BUF_DP<13>";
31"P5E_CPU0_P0_TX_BUF_DP<15>";
32"P5E_CPU0_P0_TX_BUF_DN<15>";
33"P5E_CPU0_P0_TX_BUF_DN<14>";
34"P5E_CPU0_P0_TX_BUF_DP<9>";
35"P5E_CPU0_P0_TX_BUF_DP<10>";
36"P5E_CPU0_P0_TX_BUF_DN<13>";
37"P5E_CPU0_P0_TX_BUF_DN<12>";
38"P5E_CPU0_P0_TX_BUF_DN<11>";
39"P5E_CPU0_P0_TX_BUF_C_DN<8>";
40"P5E_CPU0_P0_TX_BUF_DN<9>";
41"P5E_CPU0_P0_TX_BUF_DP<8>";
42"P5E_CPU0_P0_TX_BUF_DP<9>";
43"P5E_CPU0_P0_TX_BUF_DP<10>";
44"P5E_CPU0_P0_TX_BUF_DP<12>";
45"P5E_CPU0_P0_TX_BUF_DP<12>";
46"P5E_CPU0_P0_TX_BUF_DP<11>";
47"P5E_CPU0_P0_TX_BUF_DP<11>";
48"P5E_CPU0_P0_TX_BUF_DP<13>";
49"P5E_CPU0_P0_TX_BUF_DP<14>";
50"P5E_CPU0_P0_TX_BUF_DP<14>";
51"P5E_CPU0_P0_TX_BUF_DP<15>";
52"P5E_CPU0_P0_TX_BUF_DN<12>";
53"P5E_CPU0_P0_TX_BUF_C_DN<11>";
54"P5E_CPU0_P0_TX_BUF_C_DN<12>";
55"P5E_CPU0_P0_TX_BUF_C_DN<13>";
56"P5E_CPU0_P0_TX_BUF_DN<14>";
57"P5E_CPU0_P0_TX_BUF_DN<15>";
58"P5E_CPU0_P0_TX_BUF_C_DN<10>";
59"P5E_CPU0_P0_TX_BUF_DN<7>";
60"P5E_CPU0_P0_TX_BUF_DP<7>";
61"P5E_CPU0_P0_TX_BUF_DP<6>";
62"P5E_CPU0_P0_TX_BUF_DN<6>";
63"P5E_CPU0_P0_TX_BUF_DN<5>";
64"P5E_CPU0_P0_TX_BUF_DP<4>";
65"P5E_CPU0_P0_TX_BUF_DN<2>";
66"P5E_CPU0_P0_TX_BUF_DP<2>";
67"P5E_CPU0_P0_TX_BUF_DP<1>";
68"P5E_CPU0_P0_TX_BUF_DP<0>";
69"P5E_CPU0_P0_TX_BUF_DP<5>";
70"P5E_CPU0_P0_TX_BUF_DN<1>";
71"P5E_CPU0_P0_TX_BUF_DN<3>";
72"P5E_CPU0_P0_TX_BUF_DP<3>";
73"P5E_CPU0_P0_TX_BUF_DN<4>";
74"P5E_CPU0_P0_TX_BUF_DN<0>";
75"P5E_CPU0_P0_TX_BUF_C_DN<14>";
76"P5E_CPU0_P0_TX_BUF_C_DN<15>";
77"P5E_CPU0_P0_TX_BUF_C_DN<4>";
78"P5E_CPU0_P0_TX_BUF_C_DP<4>";
79"P5E_CPU0_P0_TX_BUF_C_DP<0>";
80"P5E_CPU0_P0_TX_BUF_C_DN<0>";
81"P5E_CPU0_P0_TX_BUF_C_DP<1>";
82"P5E_CPU0_P0_TX_BUF_C_DN<1>";
83"P5E_CPU0_P0_TX_BUF_C_DP<2>";
84"P5E_CPU0_P0_TX_BUF_C_DN<2>";
85"P5E_CPU0_P0_TX_BUF_C_DN<3>";
86"P5E_CPU0_P0_TX_BUF_C_DP<3>";
87"P5E_CPU0_P0_TX_BUF_C_DP<5>";
88"P5E_CPU0_P0_TX_BUF_C_DN<5>";
89"P5E_CPU0_P0_TX_BUF_C_DP<6>";
90"P5E_CPU0_P0_TX_BUF_C_DN<6>";
91"P5E_CPU0_P0_TX_BUF_C_DN<7>";
92"P5E_CPU0_P0_TX_BUF_C_DP<7>";
93"P5E_CPU0_P0_TX_BUF_DP<0>";
94"P5E_CPU0_P0_TX_BUF_DP<1>";
95"P5E_CPU0_P0_TX_BUF_DP<2>";
96"P5E_CPU0_P0_TX_BUF_DN<0>";
97"P5E_CPU0_P0_TX_BUF_DN<2>";
98"P5E_CPU0_P0_TX_BUF_DN<1>";
99"P5E_CPU0_P0_TX_BUF_DP<3>";
100"P5E_CPU0_P0_TX_BUF_DP<4>";
101"P5E_CPU0_P0_TX_BUF_DN<3>";
102"P5E_CPU0_P0_TX_BUF_DN<4>";
103"P5E_CPU0_P0_TX_BUF_DP<5>";
104"P5E_CPU0_P0_TX_BUF_DP<6>";
105"P5E_CPU0_P0_TX_BUF_DP<7>";
106"P5E_CPU0_P0_TX_BUF_DN<5>";
107"P5E_CPU0_P0_TX_BUF_DN<6>";
108"P5E_CPU0_P0_TX_BUF_DN<7>";
%"PT5161LRS"
"10","(-7800,4800)","0","pure_quanta","I1";
;
LOCATION"U6010"
$SEC"10"
CDS_SEC"10"
VALUE"PT5161LRS"
PART_TYPE"SMLF"
MATERIAL"IC"
CDS_LIB"pure_quanta"
CDS_LMAN_SYM_OUTLINE"-350,1450,300,-1400"
NEEDS_NO_SIZE"TRUE"
PART_NUMBER"AJ051610U03";
"B_PETN7"
$PN"CC10"17;
"B_PETP7"
$PN"CA7"41;
"B_PETN6"
$PN"BT10"16;
"B_PETP6"
$PN"BP7"42;
"B_PETN5"
$PN"BJ10"15;
"B_PETP5"
$PN"BG7"43;
"B_PETN4"
$PN"BB10"14;
"B_PETP4"
$PN"AY7"46;
"B_PETN3"
$PN"AR10"52;
"B_PETP3"
$PN"AN7"44;
"B_PETN2"
$PN"AH10"13;
"B_PETP2"
$PN"AF7"30;
"B_PETN1"
$PN"AA10"33;
"B_PETP1"
$PN"W7"49;
"B_PETN0"
$PN"P10"32;
"B_PETP0"
$PN"M7"31;
%"TAP"
"1","(-7075,4650)","0","standard","I10";
;
CDS_LIB"standard"
BODY_TYPE"PLUMBING"
HDL_TAP"TRUE";
"B \NAC \NWC"11;
"S \NAC"
BN"11"46;
%"Q_CAP_DIFFBUS"
"2","(-7000,2275)","2","pure_quanta","I100";
;
LOCATION"C6518"
$SEC"1"
CDS_SEC"1"
VALUE"DIFF BUS_0.22UF"
CDS_LMAN_SYM_OUTLINE"-25,50,25,-50"
CDS_LIB"pure_quanta"
PIN_NAMES_ROTATE"TRUE"
VOLTAGE"6.3V"
MATERIAL"X6S"
PACK_TYPE"C0201"
TOLERANCE"20%"
PART_NUMBER"SP_CH4221MEE01"
LOCATION"C6518";
"2"
$PN"2"19;
"1"
$PN"1"39;
%"Q_CAP_DIFFBUS"
"2","(-7000,2075)","2","pure_quanta","I101";
;
LOCATION"C6520"
$SEC"1"
CDS_SEC"1"
VALUE"DIFF BUS_0.22UF"
CDS_LMAN_SYM_OUTLINE"-25,50,25,-50"
CDS_LIB"pure_quanta"
PIN_NAMES_ROTATE"TRUE"
VOLTAGE"6.3V"
MATERIAL"X6S"
PACK_TYPE"C0201"
TOLERANCE"20%"
PART_NUMBER"SP_CH4221MEE01"
LOCATION"C6520";
"2"
$PN"2"40;
"1"
$PN"1"20;
%"Q_CAP_DIFFBUS"
"2","(-7000,2125)","2","pure_quanta","I102";
;
LOCATION"C6519"
$SEC"1"
CDS_SEC"1"
VALUE"DIFF BUS_0.22UF"
CDS_LMAN_SYM_OUTLINE"-25,50,25,-50"
CDS_LIB"pure_quanta"
PIN_NAMES_ROTATE"TRUE"
VOLTAGE"6.3V"
MATERIAL"X6S"
PACK_TYPE"C0201"
TOLERANCE"20%"
PART_NUMBER"SP_CH4221MEE01"
LOCATION"C6519";
"2"
$PN"2"34;
"1"
$PN"1"29;
%"TAP"
"1","(-7725,2325)","2","standard","I103";
;
CDS_LIB"standard"
BODY_TYPE"PLUMBING"
HDL_TAP"TRUE";
"B \NAC \NWC"10;
"S \NAC"
BN"8"18;
%"TAP"
"1","(-7725,2125)","2","standard","I104";
;
CDS_LIB"standard"
BODY_TYPE"PLUMBING"
HDL_TAP"TRUE";
"B \NAC \NWC"10;
"S \NAC"
BN"9"34;
%"TAP"
"1","(-7975,2275)","2","standard","I105";
;
CDS_LIB"standard"
BODY_TYPE"PLUMBING"
HDL_TAP"TRUE";
"B \NAC \NWC"8;
"S \NAC"
BN"8"19;
%"TAP"
"1","(-7975,2075)","2","standard","I106";
;
CDS_LIB"standard"
BODY_TYPE"PLUMBING"
HDL_TAP"TRUE";
"B \NAC \NWC"8;
"S \NAC"
BN"9"40;
%"TAP"
"1","(-6250,1875)","0","standard","I107";
;
CDS_LIB"standard"
BODY_TYPE"PLUMBING"
HDL_TAP"TRUE";
"B \NAC \NWC"5;
"S \NAC"
BN"10"58;
%"TAP"
"1","(-6250,1675)","0","standard","I108";
;
CDS_LIB"standard"
BODY_TYPE"PLUMBING"
HDL_TAP"TRUE";
"B \NAC \NWC"5;
"S \NAC"
BN"11"53;
%"TAP"
"1","(-6250,1475)","0","standard","I109";
;
CDS_LIB"standard"
BODY_TYPE"PLUMBING"
HDL_TAP"TRUE";
"B \NAC \NWC"5;
"S \NAC"
BN"12"54;
%"TAP"
"1","(-6875,4900)","0","standard","I11";
;
CDS_LIB"standard"
BODY_TYPE"PLUMBING"
HDL_TAP"TRUE";
"B \NAC \NWC"9;
"S \NAC"
BN"12"52;
%"TAP"
"1","(-6450,1525)","0","standard","I110";
;
CDS_LIB"standard"
BODY_TYPE"PLUMBING"
HDL_TAP"TRUE";
"B \NAC \NWC"12;
"S \NAC"
BN"12"25;
%"TAP"
"1","(-6450,1725)","0","standard","I111";
;
CDS_LIB"standard"
BODY_TYPE"PLUMBING"
HDL_TAP"TRUE";
"B \NAC \NWC"12;
"S \NAC"
BN"11"24;
%"TAP"
"1","(-6450,1925)","0","standard","I112";
;
CDS_LIB"standard"
BODY_TYPE"PLUMBING"
HDL_TAP"TRUE";
"B \NAC \NWC"12;
"S \NAC"
BN"10"22;
%"TAP"
"1","(-6250,1275)","0","standard","I113";
;
CDS_LIB"standard"
BODY_TYPE"PLUMBING"
HDL_TAP"TRUE";
"B \NAC \NWC"5;
"S \NAC"
BN"13"55;
%"TAP"
"1","(-6250,1075)","0","standard","I114";
;
CDS_LIB"standard"
BODY_TYPE"PLUMBING"
HDL_TAP"TRUE";
"B \NAC \NWC"5;
"S \NAC"
BN"14"75;
%"TAP"
"1","(-6450,925)","0","standard","I115";
;
CDS_LIB"standard"
BODY_TYPE"PLUMBING"
HDL_TAP"TRUE";
"B \NAC \NWC"12;
"S \NAC"
BN"15"28;
%"TAP"
"1","(-6450,1125)","0","standard","I116";
;
CDS_LIB"standard"
BODY_TYPE"PLUMBING"
HDL_TAP"TRUE";
"B \NAC \NWC"12;
"S \NAC"
BN"14"27;
%"TAP"
"1","(-6450,1325)","0","standard","I117";
;
CDS_LIB"standard"
BODY_TYPE"PLUMBING"
HDL_TAP"TRUE";
"B \NAC \NWC"12;
"S \NAC"
BN"13"26;
%"Q_CAP_DIFFBUS"
"2","(-7000,1875)","2","pure_quanta","I118";
;
LOCATION"C6522"
$SEC"1"
CDS_SEC"1"
VALUE"DIFF BUS_0.22UF"
CDS_LMAN_SYM_OUTLINE"-25,50,25,-50"
CDS_LIB"pure_quanta"
PIN_NAMES_ROTATE"TRUE"
VOLTAGE"6.3V"
MATERIAL"X6S"
PACK_TYPE"C0201"
TOLERANCE"20%"
PART_NUMBER"SP_CH4221MEE01"
LOCATION"C6522";
"2"
$PN"2"21;
"1"
$PN"1"58;
%"Q_CAP_DIFFBUS"
"2","(-7000,1925)","2","pure_quanta","I119";
;
LOCATION"C6521"
$SEC"1"
CDS_SEC"1"
VALUE"DIFF BUS_0.22UF"
CDS_LMAN_SYM_OUTLINE"-25,50,25,-50"
CDS_LIB"pure_quanta"
PIN_NAMES_ROTATE"TRUE"
VOLTAGE"6.3V"
MATERIAL"X6S"
PACK_TYPE"C0201"
TOLERANCE"20%"
PART_NUMBER"SP_CH4221MEE01"
LOCATION"C6521";
"2"
$PN"2"35;
"1"
$PN"1"22;
%"TAP"
"1","(-7075,5350)","0","standard","I12";
;
CDS_LIB"standard"
BODY_TYPE"PLUMBING"
HDL_TAP"TRUE";
"B \NAC \NWC"11;
"S \NAC"
BN"13"30;
%"Q_CAP_DIFFBUS"
"2","(-7000,1725)","2","pure_quanta","I120";
;
LOCATION"C6523"
$SEC"1"
CDS_SEC"1"
VALUE"DIFF BUS_0.22UF"
CDS_LMAN_SYM_OUTLINE"-25,50,25,-50"
CDS_LIB"pure_quanta"
PIN_NAMES_ROTATE"TRUE"
VOLTAGE"6.3V"
MATERIAL"X6S"
PACK_TYPE"C0201"
TOLERANCE"20%"
PART_NUMBER"SP_CH4221MEE01"
LOCATION"C6523";
"2"
$PN"2"47;
"1"
$PN"1"24;
%"Q_CAP_DIFFBUS"
"2","(-7000,1675)","2","pure_quanta","I121";
;
LOCATION"C6524"
$SEC"1"
CDS_SEC"1"
VALUE"DIFF BUS_0.22UF"
CDS_LMAN_SYM_OUTLINE"-25,50,25,-50"
CDS_LIB"pure_quanta"
PIN_NAMES_ROTATE"TRUE"
VOLTAGE"6.3V"
MATERIAL"X6S"
PACK_TYPE"C0201"
TOLERANCE"20%"
PART_NUMBER"SP_CH4221MEE01"
LOCATION"C6524";
"2"
$PN"2"38;
"1"
$PN"1"53;
%"Q_CAP_DIFFBUS"
"2","(-7000,1475)","2","pure_quanta","I122";
;
LOCATION"C6526"
$SEC"1"
CDS_SEC"1"
VALUE"DIFF BUS_0.22UF"
CDS_LIB"pure_quanta"
CDS_LMAN_SYM_OUTLINE"-25,50,25,-50"
PIN_NAMES_ROTATE"TRUE"
VOLTAGE"6.3V"
MATERIAL"X6S"
PACK_TYPE"C0201"
TOLERANCE"20%"
PART_NUMBER"SP_CH4221MEE01"
LOCATION"C6526";
"2"
$PN"2"37;
"1"
$PN"1"54;
%"Q_CAP_DIFFBUS"
"2","(-7000,1525)","2","pure_quanta","I123";
;
LOCATION"C6525"
$SEC"1"
CDS_SEC"1"
VALUE"DIFF BUS_0.22UF"
CDS_LIB"pure_quanta"
CDS_LMAN_SYM_OUTLINE"-25,50,25,-50"
PIN_NAMES_ROTATE"TRUE"
VOLTAGE"6.3V"
MATERIAL"X6S"
PACK_TYPE"C0201"
TOLERANCE"20%"
PART_NUMBER"SP_CH4221MEE01"
LOCATION"C6525";
"2"
$PN"2"45;
"1"
$PN"1"25;
%"Q_CAP_DIFFBUS"
"2","(-7000,1325)","2","pure_quanta","I124";
;
LOCATION"C6527"
$SEC"1"
CDS_SEC"1"
VALUE"DIFF BUS_0.22UF"
CDS_LMAN_SYM_OUTLINE"-25,50,25,-50"
CDS_LIB"pure_quanta"
PIN_NAMES_ROTATE"TRUE"
VOLTAGE"6.3V"
MATERIAL"X6S"
PACK_TYPE"C0201"
TOLERANCE"20%"
PART_NUMBER"SP_CH4221MEE01"
LOCATION"C6527";
"2"
$PN"2"48;
"1"
$PN"1"26;
%"Q_CAP_DIFFBUS"
"2","(-7000,1275)","2","pure_quanta","I125";
;
LOCATION"C6528"
$SEC"1"
CDS_SEC"1"
VALUE"DIFF BUS_0.22UF"
CDS_LMAN_SYM_OUTLINE"-25,50,25,-50"
CDS_LIB"pure_quanta"
PIN_NAMES_ROTATE"TRUE"
VOLTAGE"6.3V"
MATERIAL"X6S"
PACK_TYPE"C0201"
TOLERANCE"20%"
PART_NUMBER"SP_CH4221MEE01"
LOCATION"C6528";
"2"
$PN"2"36;
"1"
$PN"1"55;
%"Q_CAP_DIFFBUS"
"2","(-7000,1125)","2","pure_quanta","I126";
;
LOCATION"C6529"
$SEC"1"
CDS_SEC"1"
VALUE"DIFF BUS_0.22UF"
CDS_LIB"pure_quanta"
CDS_LMAN_SYM_OUTLINE"-25,50,25,-50"
PIN_NAMES_ROTATE"TRUE"
VOLTAGE"6.3V"
MATERIAL"X6S"
PACK_TYPE"C0201"
TOLERANCE"20%"
PART_NUMBER"SP_CH4221MEE01"
LOCATION"C6529";
"2"
$PN"2"50;
"1"
$PN"1"27;
%"Q_CAP_DIFFBUS"
"2","(-7000,1075)","2","pure_quanta","I127";
;
LOCATION"C6530"
$SEC"1"
CDS_SEC"1"
VALUE"DIFF BUS_0.22UF"
CDS_LMAN_SYM_OUTLINE"-25,50,25,-50"
CDS_LIB"pure_quanta"
PIN_NAMES_ROTATE"TRUE"
VOLTAGE"6.3V"
MATERIAL"X6S"
PACK_TYPE"C0201"
TOLERANCE"20%"
PART_NUMBER"SP_CH4221MEE01"
LOCATION"C6530";
"2"
$PN"2"56;
"1"
$PN"1"75;
%"TAP"
"1","(-6250,875)","0","standard","I128";
;
CDS_LIB"standard"
BODY_TYPE"PLUMBING"
HDL_TAP"TRUE";
"B \NAC \NWC"5;
"S \NAC"
BN"15"76;
%"Q_CAP_DIFFBUS"
"2","(-7000,925)","2","pure_quanta","I129";
;
LOCATION"C6531"
$SEC"1"
CDS_SEC"1"
VALUE"DIFF BUS_0.22UF"
CDS_LMAN_SYM_OUTLINE"-25,50,25,-50"
CDS_LIB"pure_quanta"
PIN_NAMES_ROTATE"TRUE"
VOLTAGE"6.3V"
MATERIAL"X6S"
PACK_TYPE"C0201"
TOLERANCE"20%"
PART_NUMBER"SP_CH4221MEE01"
LOCATION"C6531";
"2"
$PN"2"51;
"1"
$PN"1"28;
%"TAP"
"1","(-6875,5250)","0","standard","I13";
;
CDS_LIB"standard"
BODY_TYPE"PLUMBING"
HDL_TAP"TRUE";
"B \NAC \NWC"9;
"S \NAC"
BN"13"13;
%"Q_CAP_DIFFBUS"
"2","(-7000,875)","2","pure_quanta","I130";
;
LOCATION"C6532"
$SEC"1"
CDS_SEC"1"
VALUE"DIFF BUS_0.22UF"
CDS_LMAN_SYM_OUTLINE"-25,50,25,-50"
CDS_LIB"pure_quanta"
PIN_NAMES_ROTATE"TRUE"
VOLTAGE"6.3V"
MATERIAL"X6S"
PACK_TYPE"C0201"
TOLERANCE"20%"
PART_NUMBER"SP_CH4221MEE01"
LOCATION"C6532";
"2"
$PN"2"57;
"1"
$PN"1"76;
%"TAP"
"1","(-7725,1925)","2","standard","I131";
;
CDS_LIB"standard"
BODY_TYPE"PLUMBING"
HDL_TAP"TRUE";
"B \NAC \NWC"10;
"S \NAC"
BN"10"35;
%"TAP"
"1","(-7725,1725)","2","standard","I132";
;
CDS_LIB"standard"
BODY_TYPE"PLUMBING"
HDL_TAP"TRUE";
"B \NAC \NWC"10;
"S \NAC"
BN"11"47;
%"TAP"
"1","(-7725,1525)","2","standard","I133";
;
CDS_LIB"standard"
BODY_TYPE"PLUMBING"
HDL_TAP"TRUE";
"B \NAC \NWC"10;
"S \NAC"
BN"12"45;
%"TAP"
"1","(-7725,1325)","2","standard","I134";
;
CDS_LIB"standard"
BODY_TYPE"PLUMBING"
HDL_TAP"TRUE";
"B \NAC \NWC"10;
"S \NAC"
BN"13"48;
%"TAP"
"1","(-7725,1125)","2","standard","I135";
;
CDS_LIB"standard"
BODY_TYPE"PLUMBING"
HDL_TAP"TRUE";
"B \NAC \NWC"10;
"S \NAC"
BN"14"50;
%"TAP"
"1","(-7725,925)","2","standard","I136";
;
CDS_LIB"standard"
BODY_TYPE"PLUMBING"
HDL_TAP"TRUE";
"B \NAC \NWC"10;
"S \NAC"
BN"15"51;
%"TAP"
"1","(-7975,1875)","2","standard","I137";
;
CDS_LIB"standard"
BODY_TYPE"PLUMBING"
HDL_TAP"TRUE";
"B \NAC \NWC"8;
"S \NAC"
BN"10"21;
%"TAP"
"1","(-7975,1675)","2","standard","I138";
;
CDS_LIB"standard"
BODY_TYPE"PLUMBING"
HDL_TAP"TRUE";
"B \NAC \NWC"8;
"S \NAC"
BN"11"38;
%"TAP"
"1","(-7975,1475)","2","standard","I139";
;
CDS_LIB"standard"
BODY_TYPE"PLUMBING"
HDL_TAP"TRUE";
"B \NAC \NWC"8;
"S \NAC"
BN"12"37;
%"TAP"
"1","(-7075,5700)","0","standard","I14";
;
CDS_LIB"standard"
BODY_TYPE"PLUMBING"
HDL_TAP"TRUE";
"B \NAC \NWC"11;
"S \NAC"
BN"14"49;
%"TAP"
"1","(-7975,1275)","2","standard","I140";
;
CDS_LIB"standard"
BODY_TYPE"PLUMBING"
HDL_TAP"TRUE";
"B \NAC \NWC"8;
"S \NAC"
BN"13"36;
%"TAP"
"1","(-7975,1075)","2","standard","I141";
;
CDS_LIB"standard"
BODY_TYPE"PLUMBING"
HDL_TAP"TRUE";
"B \NAC \NWC"8;
"S \NAC"
BN"14"56;
%"TAP"
"1","(-7975,875)","2","standard","I142";
;
CDS_LIB"standard"
BODY_TYPE"PLUMBING"
HDL_TAP"TRUE";
"B \NAC \NWC"8;
"S \NAC"
BN"15"57;
%"TAP"
"1","(-7075,6050)","0","standard","I15";
;
CDS_LIB"standard"
BODY_TYPE"PLUMBING"
HDL_TAP"TRUE";
"B \NAC \NWC"11;
"S \NAC"
BN"15"31;
%"TAP"
"1","(-6875,5950)","0","standard","I16";
;
CDS_LIB"standard"
BODY_TYPE"PLUMBING"
HDL_TAP"TRUE";
"B \NAC \NWC"9;
"S \NAC"
BN"15"32;
%"TAP"
"1","(-7075,5000)","0","standard","I19";
;
CDS_LIB"standard"
BODY_TYPE"PLUMBING"
HDL_TAP"TRUE";
"B \NAC \NWC"11;
"S \NAC"
BN"12"44;
%"PT5161LRS"
"11","(-2625,4775)","0","pure_quanta","I2";
;
LOCATION"U6010"
$SEC"11"
CDS_SEC"11"
MATERIAL"IC"
VALUE"PT5161LRS"
PART_TYPE"SMLF"
NEEDS_NO_SIZE"TRUE"
CDS_LMAN_SYM_OUTLINE"-350,1450,300,-1400"
CDS_LIB"pure_quanta"
PART_NUMBER"AJ051610U03";
"B_PETN15"
$PN"EW10"74;
"B_PETP15"
$PN"EU7"68;
"B_PETN14"
$PN"EM10"70;
"B_PETP14"
$PN"EK7"67;
"B_PETN13"
$PN"EE10"65;
"B_PETP13"
$PN"EC7"66;
"B_PETN12"
$PN"DV10"71;
"B_PETP12"
$PN"DT7"72;
"B_PETN11"
$PN"DL10"73;
"B_PETP11"
$PN"DJ7"64;
"B_PETN10"
$PN"DD10"63;
"B_PETP10"
$PN"DB7"69;
"B_PETN9"
$PN"CU10"62;
"B_PETP9"
$PN"CR7"61;
"B_PETN8"
$PN"CK10"59;
"B_PETP8"
$PN"CH7"60;
%"TAP"
"1","(-6875,5600)","0","standard","I20";
;
CDS_LIB"standard"
BODY_TYPE"PLUMBING"
HDL_TAP"TRUE";
"B \NAC \NWC"9;
"S \NAC"
BN"14"33;
%"TAP"
"1","(-1700,5925)","0","standard","I25";
;
CDS_LIB"standard"
BODY_TYPE"PLUMBING"
HDL_TAP"TRUE";
"B \NAC \NWC"6;
"S \NAC"
BN"7"59;
%"TAP"
"1","(-1900,6025)","0","standard","I26";
;
CDS_LIB"standard"
BODY_TYPE"PLUMBING"
HDL_TAP"TRUE";
"B \NAC \NWC"7;
"S \NAC"
BN"7"60;
%"TAP"
"1","(-1900,5675)","0","standard","I27";
;
CDS_LIB"standard"
BODY_TYPE"PLUMBING"
HDL_TAP"TRUE";
"B \NAC \NWC"7;
"S \NAC"
BN"6"61;
%"TAP"
"1","(-1700,5575)","0","standard","I28";
;
CDS_LIB"standard"
BODY_TYPE"PLUMBING"
HDL_TAP"TRUE";
"B \NAC \NWC"6;
"S \NAC"
BN"6"62;
%"TAP"
"1","(-1900,5325)","0","standard","I29";
;
CDS_LIB"standard"
BODY_TYPE"PLUMBING"
HDL_TAP"TRUE";
"B \NAC \NWC"7;
"S \NAC"
BN"5"69;
%"TAP"
"1","(-6875,3500)","0","standard","I3";
;
CDS_LIB"standard"
BODY_TYPE"PLUMBING"
HDL_TAP"TRUE";
"B \NAC \NWC"9;
"S \NAC"
BN"8"17;
%"TAP"
"1","(-1700,5225)","0","standard","I30";
;
CDS_LIB"standard"
BODY_TYPE"PLUMBING"
HDL_TAP"TRUE";
"B \NAC \NWC"6;
"S \NAC"
BN"5"63;
%"TAP"
"1","(-1900,4975)","0","standard","I31";
;
CDS_LIB"standard"
BODY_TYPE"PLUMBING"
HDL_TAP"TRUE";
"B \NAC \NWC"7;
"S \NAC"
BN"4"64;
%"TAP"
"1","(-1700,4875)","0","standard","I32";
;
CDS_LIB"standard"
BODY_TYPE"PLUMBING"
HDL_TAP"TRUE";
"B \NAC \NWC"6;
"S \NAC"
BN"4"73;
%"TAP"
"1","(-1900,4625)","0","standard","I33";
;
CDS_LIB"standard"
BODY_TYPE"PLUMBING"
HDL_TAP"TRUE";
"B \NAC \NWC"7;
"S \NAC"
BN"3"72;
%"TAP"
"1","(-1700,4525)","0","standard","I34";
;
CDS_LIB"standard"
BODY_TYPE"PLUMBING"
HDL_TAP"TRUE";
"B \NAC \NWC"6;
"S \NAC"
BN"3"71;
%"TAP"
"1","(-1900,4275)","0","standard","I35";
;
CDS_LIB"standard"
BODY_TYPE"PLUMBING"
HDL_TAP"TRUE";
"B \NAC \NWC"7;
"S \NAC"
BN"2"66;
%"TAP"
"1","(-1700,4175)","0","standard","I36";
;
CDS_LIB"standard"
BODY_TYPE"PLUMBING"
HDL_TAP"TRUE";
"B \NAC \NWC"6;
"S \NAC"
BN"2"65;
%"TAP"
"1","(-1700,3825)","0","standard","I37";
;
CDS_LIB"standard"
BODY_TYPE"PLUMBING"
HDL_TAP"TRUE";
"B \NAC \NWC"6;
"S \NAC"
BN"1"70;
%"TAP"
"1","(-1900,3925)","0","standard","I38";
;
CDS_LIB"standard"
BODY_TYPE"PLUMBING"
HDL_TAP"TRUE";
"B \NAC \NWC"7;
"S \NAC"
BN"1"67;
%"TAP"
"1","(-1900,3575)","0","standard","I39";
;
CDS_LIB"standard"
BODY_TYPE"PLUMBING"
HDL_TAP"TRUE";
"B \NAC \NWC"7;
"S \NAC"
BN"0"68;
%"TAP"
"1","(-7075,3600)","0","standard","I4";
;
CDS_LIB"standard"
BODY_TYPE"PLUMBING"
HDL_TAP"TRUE";
"B \NAC \NWC"11;
"S \NAC"
BN"8"41;
%"TAP"
"1","(-1700,3475)","0","standard","I40";
;
CDS_LIB"standard"
BODY_TYPE"PLUMBING"
HDL_TAP"TRUE";
"B \NAC \NWC"6;
"S \NAC"
BN"0"74;
%"TAP"
"1","(-3375,825)","2","standard","I43";
;
CDS_LIB"standard"
BODY_TYPE"PLUMBING"
HDL_TAP"TRUE";
"B \NAC \NWC"1;
"S \NAC"
BN"7"108;
%"TAP"
"1","(-3375,1025)","2","standard","I44";
;
CDS_LIB"standard"
BODY_TYPE"PLUMBING"
HDL_TAP"TRUE";
"B \NAC \NWC"1;
"S \NAC"
BN"6"107;
%"TAP"
"1","(-3375,1225)","2","standard","I45";
;
CDS_LIB"standard"
BODY_TYPE"PLUMBING"
HDL_TAP"TRUE";
"B \NAC \NWC"1;
"S \NAC"
BN"5"106;
%"TAP"
"1","(-3375,1425)","2","standard","I46";
;
CDS_LIB"standard"
BODY_TYPE"PLUMBING"
HDL_TAP"TRUE";
"B \NAC \NWC"1;
"S \NAC"
BN"4"102;
%"TAP"
"1","(-3125,875)","2","standard","I47";
;
CDS_LIB"standard"
BODY_TYPE"PLUMBING"
HDL_TAP"TRUE";
"B \NAC \NWC"2;
"S \NAC"
BN"7"105;
%"TAP"
"1","(-3125,1075)","2","standard","I48";
;
CDS_LIB"standard"
BODY_TYPE"PLUMBING"
HDL_TAP"TRUE";
"B \NAC \NWC"2;
"S \NAC"
BN"6"104;
%"TAP"
"1","(-3125,1275)","2","standard","I49";
;
CDS_LIB"standard"
BODY_TYPE"PLUMBING"
HDL_TAP"TRUE";
"B \NAC \NWC"2;
"S \NAC"
BN"5"103;
%"TAP"
"1","(-7075,3950)","0","standard","I5";
;
CDS_LIB"standard"
BODY_TYPE"PLUMBING"
HDL_TAP"TRUE";
"B \NAC \NWC"11;
"S \NAC"
BN"9"42;
%"TAP"
"1","(-3125,1475)","2","standard","I50";
;
CDS_LIB"standard"
BODY_TYPE"PLUMBING"
HDL_TAP"TRUE";
"B \NAC \NWC"2;
"S \NAC"
BN"4"100;
%"TAP"
"1","(-3375,1625)","2","standard","I51";
;
CDS_LIB"standard"
BODY_TYPE"PLUMBING"
HDL_TAP"TRUE";
"B \NAC \NWC"1;
"S \NAC"
BN"3"101;
%"TAP"
"1","(-3375,1825)","2","standard","I52";
;
CDS_LIB"standard"
BODY_TYPE"PLUMBING"
HDL_TAP"TRUE";
"B \NAC \NWC"1;
"S \NAC"
BN"2"97;
%"TAP"
"1","(-3375,2025)","2","standard","I53";
;
CDS_LIB"standard"
BODY_TYPE"PLUMBING"
HDL_TAP"TRUE";
"B \NAC \NWC"1;
"S \NAC"
BN"1"98;
%"TAP"
"1","(-3375,2225)","2","standard","I54";
;
CDS_LIB"standard"
BODY_TYPE"PLUMBING"
HDL_TAP"TRUE";
"B \NAC \NWC"1;
"S \NAC"
BN"0"96;
%"TAP"
"1","(-3125,1675)","2","standard","I55";
;
CDS_LIB"standard"
BODY_TYPE"PLUMBING"
HDL_TAP"TRUE";
"B \NAC \NWC"2;
"S \NAC"
BN"3"99;
%"TAP"
"1","(-3125,1875)","2","standard","I56";
;
CDS_LIB"standard"
BODY_TYPE"PLUMBING"
HDL_TAP"TRUE";
"B \NAC \NWC"2;
"S \NAC"
BN"2"95;
%"TAP"
"1","(-3125,2075)","2","standard","I57";
;
CDS_LIB"standard"
BODY_TYPE"PLUMBING"
HDL_TAP"TRUE";
"B \NAC \NWC"2;
"S \NAC"
BN"1"94;
%"TAP"
"1","(-3125,2275)","2","standard","I58";
;
CDS_LIB"standard"
BODY_TYPE"PLUMBING"
HDL_TAP"TRUE";
"B \NAC \NWC"2;
"S \NAC"
BN"0"93;
%"Q_CAP_DIFFBUS"
"2","(-2400,825)","2","pure_quanta","I59";
;
LOCATION"C6516"
$SEC"1"
CDS_SEC"1"
VALUE"DIFF BUS_0.22UF"
TOLERANCE"20%"
PACK_TYPE"C0201"
MATERIAL"X6S"
VOLTAGE"6.3V"
PIN_NAMES_ROTATE"TRUE"
CDS_LIB"pure_quanta"
CDS_LMAN_SYM_OUTLINE"-25,50,25,-50"
PART_NUMBER"SP_CH4221MEE01"
LOCATION"C6516";
"2"
$PN"2"108;
"1"
$PN"1"91;
%"TAP"
"1","(-6875,3850)","0","standard","I6";
;
CDS_LIB"standard"
BODY_TYPE"PLUMBING"
HDL_TAP"TRUE";
"B \NAC \NWC"9;
"S \NAC"
BN"9"16;
%"Q_CAP_DIFFBUS"
"2","(-2400,1075)","2","pure_quanta","I60";
;
LOCATION"C6513"
$SEC"1"
CDS_SEC"1"
VALUE"DIFF BUS_0.22UF"
TOLERANCE"20%"
PACK_TYPE"C0201"
MATERIAL"X6S"
VOLTAGE"6.3V"
PIN_NAMES_ROTATE"TRUE"
CDS_LMAN_SYM_OUTLINE"-25,50,25,-50"
CDS_LIB"pure_quanta"
PART_NUMBER"SP_CH4221MEE01"
LOCATION"C6513";
"2"
$PN"2"104;
"1"
$PN"1"89;
%"Q_CAP_DIFFBUS"
"2","(-2400,1025)","2","pure_quanta","I61";
;
LOCATION"C6514"
$SEC"1"
CDS_SEC"1"
VALUE"DIFF BUS_0.22UF"
TOLERANCE"20%"
PACK_TYPE"C0201"
MATERIAL"X6S"
VOLTAGE"6.3V"
PIN_NAMES_ROTATE"TRUE"
CDS_LIB"pure_quanta"
CDS_LMAN_SYM_OUTLINE"-25,50,25,-50"
PART_NUMBER"SP_CH4221MEE01"
LOCATION"C6514";
"2"
$PN"2"107;
"1"
$PN"1"90;
%"Q_CAP_DIFFBUS"
"2","(-2400,875)","2","pure_quanta","I62";
;
LOCATION"C6515"
$SEC"1"
CDS_SEC"1"
VALUE"DIFF BUS_0.22UF"
TOLERANCE"20%"
PACK_TYPE"C0201"
MATERIAL"X6S"
VOLTAGE"6.3V"
PIN_NAMES_ROTATE"TRUE"
CDS_LIB"pure_quanta"
CDS_LMAN_SYM_OUTLINE"-25,50,25,-50"
PART_NUMBER"SP_CH4221MEE01"
LOCATION"C6515";
"2"
$PN"2"105;
"1"
$PN"1"92;
%"Q_CAP_DIFFBUS"
"2","(-2400,1275)","2","pure_quanta","I63";
;
LOCATION"C6511"
$SEC"1"
CDS_SEC"1"
VALUE"DIFF BUS_0.22UF"
TOLERANCE"20%"
PACK_TYPE"C0201"
MATERIAL"X6S"
VOLTAGE"6.3V"
PIN_NAMES_ROTATE"TRUE"
CDS_LIB"pure_quanta"
CDS_LMAN_SYM_OUTLINE"-25,50,25,-50"
PART_NUMBER"SP_CH4221MEE01"
LOCATION"C6511";
"2"
$PN"2"103;
"1"
$PN"1"87;
%"Q_CAP_DIFFBUS"
"2","(-2400,1225)","2","pure_quanta","I64";
;
LOCATION"C6512"
$SEC"1"
CDS_SEC"1"
VALUE"DIFF BUS_0.22UF"
TOLERANCE"20%"
PACK_TYPE"C0201"
MATERIAL"X6S"
VOLTAGE"6.3V"
PIN_NAMES_ROTATE"TRUE"
CDS_LIB"pure_quanta"
CDS_LMAN_SYM_OUTLINE"-25,50,25,-50"
PART_NUMBER"SP_CH4221MEE01"
LOCATION"C6512";
"2"
$PN"2"106;
"1"
$PN"1"88;
%"Q_CAP_DIFFBUS"
"2","(-2400,1475)","2","pure_quanta","I65";
;
LOCATION"C6509"
$SEC"1"
CDS_SEC"1"
VALUE"DIFF BUS_0.22UF"
TOLERANCE"20%"
PACK_TYPE"C0201"
MATERIAL"X6S"
VOLTAGE"6.3V"
PIN_NAMES_ROTATE"TRUE"
CDS_LMAN_SYM_OUTLINE"-25,50,25,-50"
CDS_LIB"pure_quanta"
PART_NUMBER"SP_CH4221MEE01"
LOCATION"C6509";
"2"
$PN"2"100;
"1"
$PN"1"78;
%"Q_CAP_DIFFBUS"
"2","(-2400,1425)","2","pure_quanta","I66";
;
LOCATION"C6510"
$SEC"1"
CDS_SEC"1"
VALUE"DIFF BUS_0.22UF"
TOLERANCE"20%"
PACK_TYPE"C0201"
MATERIAL"X6S"
VOLTAGE"6.3V"
PIN_NAMES_ROTATE"TRUE"
CDS_LMAN_SYM_OUTLINE"-25,50,25,-50"
CDS_LIB"pure_quanta"
PART_NUMBER"SP_CH4221MEE01"
LOCATION"C6510";
"2"
$PN"2"102;
"1"
$PN"1"77;
%"TAP"
"1","(-1850,1075)","0","standard","I67";
;
CDS_LIB"standard"
BODY_TYPE"PLUMBING"
HDL_TAP"TRUE";
"B \NAC \NWC"3;
"S \NAC"
BN"6"89;
%"TAP"
"1","(-1850,875)","0","standard","I68";
;
CDS_LIB"standard"
BODY_TYPE"PLUMBING"
HDL_TAP"TRUE";
"B \NAC \NWC"3;
"S \NAC"
BN"7"92;
%"TAP"
"1","(-1850,1275)","0","standard","I69";
;
CDS_LIB"standard"
BODY_TYPE"PLUMBING"
HDL_TAP"TRUE";
"B \NAC \NWC"3;
"S \NAC"
BN"5"87;
%"TAP"
"1","(-7075,4300)","0","standard","I7";
;
CDS_LIB"standard"
BODY_TYPE"PLUMBING"
HDL_TAP"TRUE";
"B \NAC \NWC"11;
"S \NAC"
BN"10"43;
%"TAP"
"1","(-1850,1475)","0","standard","I70";
;
CDS_LIB"standard"
BODY_TYPE"PLUMBING"
HDL_TAP"TRUE";
"B \NAC \NWC"3;
"S \NAC"
BN"4"78;
%"Q_CAP_DIFFBUS"
"2","(-2400,1625)","2","pure_quanta","I71";
;
LOCATION"C6508"
$SEC"1"
CDS_SEC"1"
VALUE"DIFF BUS_0.22UF"
TOLERANCE"20%"
PACK_TYPE"C0201"
MATERIAL"X6S"
VOLTAGE"6.3V"
PIN_NAMES_ROTATE"TRUE"
CDS_LIB"pure_quanta"
CDS_LMAN_SYM_OUTLINE"-25,50,25,-50"
PART_NUMBER"SP_CH4221MEE01"
LOCATION"C6508";
"2"
$PN"2"101;
"1"
$PN"1"85;
%"Q_CAP_DIFFBUS"
"2","(-2400,1825)","2","pure_quanta","I72";
;
LOCATION"C6506"
$SEC"1"
CDS_SEC"1"
VALUE"DIFF BUS_0.22UF"
TOLERANCE"20%"
PACK_TYPE"C0201"
MATERIAL"X6S"
VOLTAGE"6.3V"
PIN_NAMES_ROTATE"TRUE"
CDS_LIB"pure_quanta"
CDS_LMAN_SYM_OUTLINE"-25,50,25,-50"
PART_NUMBER"SP_CH4221MEE01"
LOCATION"C6506";
"2"
$PN"2"97;
"1"
$PN"1"84;
%"Q_CAP_DIFFBUS"
"2","(-2400,1675)","2","pure_quanta","I73";
;
LOCATION"C6507"
$SEC"1"
CDS_SEC"1"
VALUE"DIFF BUS_0.22UF"
TOLERANCE"20%"
PACK_TYPE"C0201"
MATERIAL"X6S"
VOLTAGE"6.3V"
PIN_NAMES_ROTATE"TRUE"
CDS_LIB"pure_quanta"
CDS_LMAN_SYM_OUTLINE"-25,50,25,-50"
PART_NUMBER"SP_CH4221MEE01"
LOCATION"C6507";
"2"
$PN"2"99;
"1"
$PN"1"86;
%"Q_CAP_DIFFBUS"
"2","(-2400,1875)","2","pure_quanta","I74";
;
LOCATION"C6505"
$SEC"1"
CDS_SEC"1"
VALUE"DIFF BUS_0.22UF"
TOLERANCE"20%"
PACK_TYPE"C0201"
MATERIAL"X6S"
VOLTAGE"6.3V"
PIN_NAMES_ROTATE"TRUE"
CDS_LIB"pure_quanta"
CDS_LMAN_SYM_OUTLINE"-25,50,25,-50"
PART_NUMBER"SP_CH4221MEE01"
LOCATION"C6505";
"2"
$PN"2"95;
"1"
$PN"1"83;
%"Q_CAP_DIFFBUS"
"2","(-2400,2075)","2","pure_quanta","I75";
;
LOCATION"C6503"
$SEC"1"
CDS_SEC"1"
VALUE"DIFF BUS_0.22UF"
TOLERANCE"20%"
PACK_TYPE"C0201"
MATERIAL"X6S"
VOLTAGE"6.3V"
PIN_NAMES_ROTATE"TRUE"
CDS_LIB"pure_quanta"
CDS_LMAN_SYM_OUTLINE"-25,50,25,-50"
PART_NUMBER"SP_CH4221MEE01"
LOCATION"C6503";
"2"
$PN"2"94;
"1"
$PN"1"81;
%"Q_CAP_DIFFBUS"
"2","(-2400,2025)","2","pure_quanta","I76";
;
LOCATION"C6504"
$SEC"1"
CDS_SEC"1"
VALUE"DIFF BUS_0.22UF"
TOLERANCE"20%"
PACK_TYPE"C0201"
MATERIAL"X6S"
VOLTAGE"6.3V"
PIN_NAMES_ROTATE"TRUE"
CDS_LIB"pure_quanta"
CDS_LMAN_SYM_OUTLINE"-25,50,25,-50"
PART_NUMBER"SP_CH4221MEE01"
LOCATION"C6504";
"2"
$PN"2"98;
"1"
$PN"1"82;
%"Q_CAP_DIFFBUS"
"2","(-2400,2275)","2","pure_quanta","I77";
;
LOCATION"C6501"
$SEC"1"
CDS_SEC"1"
MATERIAL"X6S"
PACK_TYPE"C0201"
VALUE"DIFF BUS_0.22UF"
TOLERANCE"20%"
VOLTAGE"6.3V"
PIN_NAMES_ROTATE"TRUE"
CDS_LMAN_SYM_OUTLINE"-25,50,25,-50"
CDS_LIB"pure_quanta"
PART_NUMBER"SP_CH4221MEE01"
LOCATION"C6501";
"2"
$PN"2"93;
"1"
$PN"1"79;
%"Q_CAP_DIFFBUS"
"2","(-2400,2225)","2","pure_quanta","I78";
;
LOCATION"C6502"
$SEC"1"
CDS_SEC"1"
VALUE"DIFF BUS_0.22UF"
TOLERANCE"20%"
PACK_TYPE"C0201"
MATERIAL"X6S"
VOLTAGE"6.3V"
PIN_NAMES_ROTATE"TRUE"
CDS_LIB"pure_quanta"
CDS_LMAN_SYM_OUTLINE"-25,50,25,-50"
PART_NUMBER"SP_CH4221MEE01"
LOCATION"C6502";
"2"
$PN"2"96;
"1"
$PN"1"80;
%"TAP"
"1","(-1850,1675)","0","standard","I79";
;
CDS_LIB"standard"
BODY_TYPE"PLUMBING"
HDL_TAP"TRUE";
"B \NAC \NWC"3;
"S \NAC"
BN"3"86;
%"TAP"
"1","(-6875,4200)","0","standard","I8";
;
CDS_LIB"standard"
BODY_TYPE"PLUMBING"
HDL_TAP"TRUE";
"B \NAC \NWC"9;
"S \NAC"
BN"10"15;
%"TAP"
"1","(-1850,1875)","0","standard","I80";
;
CDS_LIB"standard"
BODY_TYPE"PLUMBING"
HDL_TAP"TRUE";
"B \NAC \NWC"3;
"S \NAC"
BN"2"83;
%"TAP"
"1","(-1850,2275)","0","standard","I81";
;
CDS_LIB"standard"
BODY_TYPE"PLUMBING"
HDL_TAP"TRUE";
"B \NAC \NWC"3;
"S \NAC"
BN"0"79;
%"TAP"
"1","(-1650,825)","0","standard","I82";
;
CDS_LIB"standard"
BODY_TYPE"PLUMBING"
HDL_TAP"TRUE";
"B \NAC \NWC"4;
"S \NAC"
BN"7"91;
%"TAP"
"1","(-1650,1025)","0","standard","I83";
;
CDS_LIB"standard"
BODY_TYPE"PLUMBING"
HDL_TAP"TRUE";
"B \NAC \NWC"4;
"S \NAC"
BN"6"90;
%"TAP"
"1","(-1650,1225)","0","standard","I84";
;
CDS_LIB"standard"
BODY_TYPE"PLUMBING"
HDL_TAP"TRUE";
"B \NAC \NWC"4;
"S \NAC"
BN"5"88;
%"TAP"
"1","(-1650,1425)","0","standard","I85";
;
CDS_LIB"standard"
BODY_TYPE"PLUMBING"
HDL_TAP"TRUE";
"B \NAC \NWC"4;
"S \NAC"
BN"4"77;
%"TAP"
"1","(-1650,1625)","0","standard","I86";
;
CDS_LIB"standard"
BODY_TYPE"PLUMBING"
HDL_TAP"TRUE";
"B \NAC \NWC"4;
"S \NAC"
BN"3"85;
%"TAP"
"1","(-1650,1825)","0","standard","I87";
;
CDS_LIB"standard"
BODY_TYPE"PLUMBING"
HDL_TAP"TRUE";
"B \NAC \NWC"4;
"S \NAC"
BN"2"84;
%"TAP"
"1","(-1650,2225)","0","standard","I88";
;
CDS_LIB"standard"
BODY_TYPE"PLUMBING"
HDL_TAP"TRUE";
"B \NAC \NWC"4;
"S \NAC"
BN"0"80;
%"TAP"
"1","(-6875,4550)","0","standard","I9";
;
CDS_LIB"standard"
BODY_TYPE"PLUMBING"
HDL_TAP"TRUE";
"B \NAC \NWC"9;
"S \NAC"
BN"11"14;
%"TAP"
"1","(-1650,2025)","0","standard","I91";
;
CDS_LIB"standard"
BODY_TYPE"PLUMBING"
HDL_TAP"TRUE";
"B \NAC \NWC"4;
"S \NAC"
BN"1"82;
%"TAP"
"1","(-1850,2075)","0","standard","I92";
;
CDS_LIB"standard"
BODY_TYPE"PLUMBING"
HDL_TAP"TRUE";
"B \NAC \NWC"3;
"S \NAC"
BN"1"81;
%"TAP"
"1","(-6250,2275)","0","standard","I95";
;
CDS_LIB"standard"
BODY_TYPE"PLUMBING"
HDL_TAP"TRUE";
"B \NAC \NWC"5;
"S \NAC"
BN"8"39;
%"TAP"
"1","(-6250,2075)","0","standard","I96";
;
CDS_LIB"standard"
BODY_TYPE"PLUMBING"
HDL_TAP"TRUE";
"B \NAC \NWC"5;
"S \NAC"
BN"9"20;
%"TAP"
"1","(-6450,2125)","0","standard","I97";
;
CDS_LIB"standard"
BODY_TYPE"PLUMBING"
HDL_TAP"TRUE";
"B \NAC \NWC"12;
"S \NAC"
BN"9"29;
%"TAP"
"1","(-6450,2325)","0","standard","I98";
;
CDS_LIB"standard"
BODY_TYPE"PLUMBING"
HDL_TAP"TRUE";
"B \NAC \NWC"12;
"S \NAC"
BN"8"23;
%"Q_CAP_DIFFBUS"
"2","(-7000,2325)","2","pure_quanta","I99";
;
LOCATION"C6517"
$SEC"1"
CDS_SEC"1"
VOLTAGE"6.3V"
MATERIAL"X6S"
TOLERANCE"20%"
PACK_TYPE"C0201"
VALUE"DIFF BUS_0.22UF"
CDS_LIB"pure_quanta"
CDS_LMAN_SYM_OUTLINE"-25,50,25,-50"
PIN_NAMES_ROTATE"TRUE"
PART_NUMBER"SP_CH4221MEE01"
LOCATION"C6517";
"2"
$PN"2"18;
"1"
$PN"1"23;
END.
